(kicad_pcb
	(version 20260206)
	(generator "pcbnew")
	(generator_version "10.0")
	(general
		(thickness 1.6)
		(legacy_teardrops no)
	)
	(paper "A4")
	(title_block
		(title "01162023_DA0F0TEBIF0_F0T_Expander_BD_F_brd_V02_OCP.brd")
		(comment 1 "Grand Teton / footprints 5945-5950 of 9728")
	)
	(layers
		(0 "F.Cu" signal "TOP")
		(4 "In1.Cu" signal "GND")
		(6 "In2.Cu" signal "VCC")
		(8 "In3.Cu" signal "VCC1")
		(10 "In4.Cu" signal "GND1")
		(12 "In5.Cu" signal "IN1")
		(14 "In6.Cu" signal "GND2")
		(16 "In7.Cu" signal "IN2")
		(18 "In8.Cu" signal "GND3")
		(20 "In9.Cu" signal "IN3")
		(22 "In10.Cu" signal "GND4")
		(24 "In11.Cu" signal "IN4")
		(26 "In12.Cu" signal "GND5")
		(28 "In13.Cu" signal "IN5")
		(30 "In14.Cu" signal "GND6")
		(32 "In15.Cu" signal "IN6")
		(34 "In16.Cu" signal "GND7")
		(2 "B.Cu" signal "BOTTOM")
		(9 "F.Adhes" user "F.Adhesive")
		(11 "B.Adhes" user "B.Adhesive")
		(13 "F.Paste" user "Package Geometry/Pastemask Top")
		(15 "B.Paste" user "Package Geometry/Pastemask Bottom")
		(5 "F.SilkS" user "Ref Des/Silkscreen Top")
		(7 "B.SilkS" user "Ref Des/Silkscreen Bottom")
		(1 "F.Mask" user "Board Geometry/Soldermask Top")
		(3 "B.Mask" user "Board Geometry/Soldermask Bottom")
		(17 "Dwgs.User" user "User.Drawings")
		(19 "Cmts.User" user "User.Comments")
		(21 "Eco1.User" user "User.Eco1")
		(23 "Eco2.User" user "User.Eco2")
		(25 "Edge.Cuts" user "Board Geometry/Outline")
		(27 "Margin" user)
		(31 "F.CrtYd" user "Package Geometry/Place Bound Top")
		(29 "B.CrtYd" user "Package Geometry/Place Bound Bottom")
		(35 "F.Fab" user "Ref Des/Assembly Top")
		(33 "B.Fab" user "Ref Des/Assembly Bottom")
	)
	(footprint ""
		(layer "F.Cu")
		(at 308.58333 -49.94148)
		(property "Reference" "R621"
			(at 0 0 0)
			(layer "F.SilkS")
			(hide yes)
			(effects
				(font
					(size 1.27 1.27)
				)
			)
		)
		(property "Value" ""
			(at 0 0 0)
			(layer "F.Fab")
			(effects
				(font
					(size 1.27 1.27)
				)
			)
		)
		(duplicate_pad_numbers_are_jumpers no)
		(fp_line
			(start -0.7874 -0.4064)
			(end 0.7874 -0.4064)
			(stroke
				(width 0.1524)
				(type default)
			)
			(layer "F.SilkS")
		)
		(fp_line
			(start -0.7874 0.4064)
			(end -0.7874 -0.4064)
			(stroke
				(width 0.1524)
				(type default)
			)
			(layer "F.SilkS")
		)
		(fp_line
			(start 0.7874 -0.4064)
			(end 0.7874 0.4064)
			(stroke
				(width 0.1524)
				(type default)
			)
			(layer "F.SilkS")
		)
		(fp_line
			(start 0.7874 0.4064)
			(end -0.7874 0.4064)
			(stroke
				(width 0.1524)
				(type default)
			)
			(layer "F.SilkS")
		)
		(fp_line
			(start -0.67945 -0.305054)
			(end -0.12065 -0.305054)
			(stroke
				(width 0.1)
				(type default)
			)
			(layer "F.Fab")
		)
		(fp_line
			(start -0.67945 0.3048)
			(end -0.67945 -0.305054)
			(stroke
				(width 0.1)
				(type default)
			)
			(layer "F.Fab")
		)
		(fp_line
			(start -0.12065 -0.305054)
			(end -0.12065 -0.2794)
			(stroke
				(width 0.1)
				(type default)
			)
			(layer "F.Fab")
		)
		(fp_line
			(start -0.12065 -0.2794)
			(end 0.12065 -0.2794)
			(stroke
				(width 0.1)
				(type default)
			)
			(layer "F.Fab")
		)
		(fp_line
			(start -0.12065 0.2794)
			(end -0.12065 0.3048)
			(stroke
				(width 0.1)
				(type default)
			)
			(layer "F.Fab")
		)
		(fp_line
			(start -0.12065 0.3048)
			(end -0.67945 0.3048)
			(stroke
				(width 0.1)
				(type default)
			)
			(layer "F.Fab")
		)
		(fp_line
			(start 0.120396 0.2794)
			(end -0.12065 0.2794)
			(stroke
				(width 0.1)
				(type default)
			)
			(layer "F.Fab")
		)
		(fp_line
			(start 0.120396 0.3048)
			(end 0.120396 0.2794)
			(stroke
				(width 0.1)
				(type default)
			)
			(layer "F.Fab")
		)
		(fp_line
			(start 0.12065 -0.3048)
			(end 0.67945 -0.3048)
			(stroke
				(width 0.1)
				(type default)
			)
			(layer "F.Fab")
		)
		(fp_line
			(start 0.12065 -0.2794)
			(end 0.12065 -0.3048)
			(stroke
				(width 0.1)
				(type default)
			)
			(layer "F.Fab")
		)
		(fp_line
			(start 0.67945 -0.3048)
			(end 0.67945 0.3048)
			(stroke
				(width 0.1)
				(type default)
			)
			(layer "F.Fab")
		)
		(fp_line
			(start 0.67945 0.3048)
			(end 0.120396 0.3048)
			(stroke
				(width 0.1)
				(type default)
			)
			(layer "F.Fab")
		)
		(pad "1" smd circle
			(at -0.40005 0)
			(size 0 0)
			(layers "F.Cu" "F.Mask" "F.Paste")
			(net "SMB_BIC_I2C6_MUX_SSD_8_15_ADC_R_SCL")
		)
		(pad "2" smd circle
			(at 0.40005 0)
			(size 0 0)
			(layers "F.Cu" "F.Mask" "F.Paste")
			(net "SMB_SSD10_ADC_SCL")
		)
	)
	(footprint ""
		(layer "F.Cu")
		(at 112.734344 -180.644546)
		(property "Reference" "PC23"
			(at 0 0 0)
			(layer "F.SilkS")
			(hide yes)
			(effects
				(font
					(size 1.27 1.27)
				)
			)
		)
		(property "Value" ""
			(at 0 0 0)
			(layer "F.Fab")
			(effects
				(font
					(size 1.27 1.27)
				)
			)
		)
		(duplicate_pad_numbers_are_jumpers no)
		(fp_line
			(start -0.7874 -0.4064)
			(end 0.7874 -0.4064)
			(stroke
				(width 0.1524)
				(type default)
			)
			(layer "F.SilkS")
		)
		(fp_line
			(start -0.7874 0.4064)
			(end -0.7874 -0.4064)
			(stroke
				(width 0.1524)
				(type default)
			)
			(layer "F.SilkS")
		)
		(fp_line
			(start 0.7874 -0.4064)
			(end 0.7874 0.4064)
			(stroke
				(width 0.1524)
				(type default)
			)
			(layer "F.SilkS")
		)
		(fp_line
			(start 0.7874 0.4064)
			(end -0.7874 0.4064)
			(stroke
				(width 0.1524)
				(type default)
			)
			(layer "F.SilkS")
		)
		(fp_line
			(start -0.67945 -0.305054)
			(end -0.12065 -0.305054)
			(stroke
				(width 0.1)
				(type default)
			)
			(layer "F.Fab")
		)
		(fp_line
			(start -0.67945 0.3048)
			(end -0.67945 -0.305054)
			(stroke
				(width 0.1)
				(type default)
			)
			(layer "F.Fab")
		)
		(fp_line
			(start -0.12065 -0.305054)
			(end -0.12065 -0.2794)
			(stroke
				(width 0.1)
				(type default)
			)
			(layer "F.Fab")
		)
		(fp_line
			(start -0.12065 -0.2794)
			(end 0.12065 -0.2794)
			(stroke
				(width 0.1)
				(type default)
			)
			(layer "F.Fab")
		)
		(fp_line
			(start -0.12065 0.2794)
			(end -0.12065 0.3048)
			(stroke
				(width 0.1)
				(type default)
			)
			(layer "F.Fab")
		)
		(fp_line
			(start -0.12065 0.3048)
			(end -0.67945 0.3048)
			(stroke
				(width 0.1)
				(type default)
			)
			(layer "F.Fab")
		)
		(fp_line
			(start 0.120396 0.2794)
			(end -0.12065 0.2794)
			(stroke
				(width 0.1)
				(type default)
			)
			(layer "F.Fab")
		)
		(fp_line
			(start 0.120396 0.3048)
			(end 0.120396 0.2794)
			(stroke
				(width 0.1)
				(type default)
			)
			(layer "F.Fab")
		)
		(fp_line
			(start 0.12065 -0.3048)
			(end 0.67945 -0.3048)
			(stroke
				(width 0.1)
				(type default)
			)
			(layer "F.Fab")
		)
		(fp_line
			(start 0.12065 -0.2794)
			(end 0.12065 -0.3048)
			(stroke
				(width 0.1)
				(type default)
			)
			(layer "F.Fab")
		)
		(fp_line
			(start 0.67945 -0.3048)
			(end 0.67945 0.3048)
			(stroke
				(width 0.1)
				(type default)
			)
			(layer "F.Fab")
		)
		(fp_line
			(start 0.67945 0.3048)
			(end 0.120396 0.3048)
			(stroke
				(width 0.1)
				(type default)
			)
			(layer "F.Fab")
		)
		(pad "1" smd circle
			(at -0.40005 0)
			(size 0 0)
			(layers "F.Cu" "F.Mask" "F.Paste")
			(net "P12V_AUX")
		)
		(pad "2" smd circle
			(at 0.40005 0)
			(size 0 0)
			(layers "F.Cu" "F.Mask" "F.Paste")
			(net "GND")
		)
	)
	(footprint ""
		(layer "F.Cu")
		(at 199.647302 -224.356676)
		(property "Reference" "J59"
			(at -1.4224 -4.562348 0)
			(unlocked yes)
			(layer "F.SilkS")
			(effects
				(font
					(size 0.7874 0.5842)
					(thickness 0.1524)
				)
				(justify left)
			)
		)
		(property "Value" ""
			(at 0 0 0)
			(layer "F.Fab")
			(effects
				(font
					(size 1.27 1.27)
				)
			)
		)
		(duplicate_pad_numbers_are_jumpers no)
		(fp_line
			(start -1.27 -3.81)
			(end 1.27 -3.81)
			(stroke
				(width 0.1524)
				(type default)
			)
			(layer "F.SilkS")
		)
		(fp_line
			(start -1.27 -0.7747)
			(end -1.27 -3.81)
			(stroke
				(width 0.1524)
				(type default)
			)
			(layer "F.SilkS")
		)
		(fp_line
			(start -1.27 3.81)
			(end -1.27 0.7747)
			(stroke
				(width 0.1524)
				(type default)
			)
			(layer "F.SilkS")
		)
		(fp_line
			(start 1.27 -3.81)
			(end 1.27 -3.3147)
			(stroke
				(width 0.1524)
				(type default)
			)
			(layer "F.SilkS")
		)
		(fp_line
			(start 1.27 -1.7653)
			(end 1.27 1.7653)
			(stroke
				(width 0.1524)
				(type default)
			)
			(layer "F.SilkS")
		)
		(fp_line
			(start 1.27 3.3147)
			(end 1.27 3.81)
			(stroke
				(width 0.1524)
				(type default)
			)
			(layer "F.SilkS")
		)
		(fp_line
			(start 1.27 3.81)
			(end -1.27 3.81)
			(stroke
				(width 0.1524)
				(type default)
			)
			(layer "F.SilkS")
		)
		(fp_poly
			(pts
				(xy 4.3942 -3.048) (xy 4.3942 -2.032) (xy 3.3782 -2.54)
			)
			(stroke
				(width 0)
				(type default)
			)
			(fill yes)
			(layer "F.SilkS")
		)
		(fp_line
			(start -1.27 -3.81)
			(end -1.27 3.81)
			(stroke
				(width 0.1)
				(type default)
			)
			(layer "F.Fab")
		)
		(fp_line
			(start -1.27 3.81)
			(end 1.27 3.81)
			(stroke
				(width 0.1)
				(type default)
			)
			(layer "F.Fab")
		)
		(fp_line
			(start 1.27 -3.81)
			(end -1.27 -3.81)
			(stroke
				(width 0.1)
				(type default)
			)
			(layer "F.Fab")
		)
		(fp_line
			(start 1.27 3.81)
			(end 1.27 -3.81)
			(stroke
				(width 0.1)
				(type default)
			)
			(layer "F.Fab")
		)
		(fp_poly
			(pts
				(xy 4.3942 -3.048) (xy 4.3942 -2.032) (xy 3.3782 -2.54)
			)
			(stroke
				(width 0)
				(type default)
			)
			(fill yes)
			(layer "F.Fab")
		)
		(fp_text user "3"
			(at 3.921252 2.54 90)
			(unlocked yes)
			(layer "F.SilkS")
			(effects
				(font
					(size 0.7874 0.5842)
					(thickness 0.1524)
				)
			)
		)
		(fp_text user "3"
			(at 3.921252 2.54 90)
			(unlocked yes)
			(layer "F.Fab")
			(effects
				(font
					(size 0.7874 0.5842)
					(thickness 0.1524)
				)
			)
		)
		(pad "1" smd rect
			(at 1.459992 -2.54 90)
			(size 1.27 3.429)
			(layers "F.Cu" "F.Mask" "F.Paste")
			(net "PD_BIC_UART_SEL")
		)
		(pad "2" smd rect
			(at -1.459992 0 90)
			(size 1.27 3.429)
			(layers "F.Cu" "F.Mask" "F.Paste")
			(net "BIC_UART_HW_SEL1")
		)
		(pad "3" smd rect
			(at 1.459992 2.54 90)
			(size 1.27 3.429)
			(layers "F.Cu" "F.Mask" "F.Paste")
			(net "PU_BIC_UART_SEL")
		)
	)
	(footprint ""
		(layer "F.Cu")
		(at 218.599512 -231.416606 90)
		(property "Reference" "R4550"
			(at 0 0 90)
			(layer "F.SilkS")
			(hide yes)
			(effects
				(font
					(size 1.27 1.27)
				)
			)
		)
		(property "Value" ""
			(at 0 0 90)
			(layer "F.Fab")
			(effects
				(font
					(size 1.27 1.27)
				)
			)
		)
		(duplicate_pad_numbers_are_jumpers no)
		(fp_line
			(start 0.7874 -0.4064)
			(end 0.7874 0.4064)
			(stroke
				(width 0.1524)
				(type default)
			)
			(layer "F.SilkS")
		)
		(fp_line
			(start -0.7874 -0.4064)
			(end 0.7874 -0.4064)
			(stroke
				(width 0.1524)
				(type default)
			)
			(layer "F.SilkS")
		)
		(fp_line
			(start 0.7874 0.4064)
			(end -0.7874 0.4064)
			(stroke
				(width 0.1524)
				(type default)
			)
			(layer "F.SilkS")
		)
		(fp_line
			(start -0.7874 0.4064)
			(end -0.7874 -0.4064)
			(stroke
				(width 0.1524)
				(type default)
			)
			(layer "F.SilkS")
		)
		(fp_line
			(start -0.12065 -0.305054)
			(end -0.12065 -0.2794)
			(stroke
				(width 0.1)
				(type default)
			)
			(layer "F.Fab")
		)
		(fp_line
			(start -0.67945 -0.305054)
			(end -0.12065 -0.305054)
			(stroke
				(width 0.1)
				(type default)
			)
			(layer "F.Fab")
		)
		(fp_line
			(start 0.67945 -0.3048)
			(end 0.67945 0.3048)
			(stroke
				(width 0.1)
				(type default)
			)
			(layer "F.Fab")
		)
		(fp_line
			(start 0.12065 -0.3048)
			(end 0.67945 -0.3048)
			(stroke
				(width 0.1)
				(type default)
			)
			(layer "F.Fab")
		)
		(fp_line
			(start 0.12065 -0.2794)
			(end 0.12065 -0.3048)
			(stroke
				(width 0.1)
				(type default)
			)
			(layer "F.Fab")
		)
		(fp_line
			(start -0.12065 -0.2794)
			(end 0.12065 -0.2794)
			(stroke
				(width 0.1)
				(type default)
			)
			(layer "F.Fab")
		)
		(fp_line
			(start 0.120396 0.2794)
			(end -0.12065 0.2794)
			(stroke
				(width 0.1)
				(type default)
			)
			(layer "F.Fab")
		)
		(fp_line
			(start -0.12065 0.2794)
			(end -0.12065 0.3048)
			(stroke
				(width 0.1)
				(type default)
			)
			(layer "F.Fab")
		)
		(fp_line
			(start 0.67945 0.3048)
			(end 0.120396 0.3048)
			(stroke
				(width 0.1)
				(type default)
			)
			(layer "F.Fab")
		)
		(fp_line
			(start 0.120396 0.3048)
			(end 0.120396 0.2794)
			(stroke
				(width 0.1)
				(type default)
			)
			(layer "F.Fab")
		)
		(fp_line
			(start -0.12065 0.3048)
			(end -0.67945 0.3048)
			(stroke
				(width 0.1)
				(type default)
			)
			(layer "F.Fab")
		)
		(fp_line
			(start -0.67945 0.3048)
			(end -0.67945 -0.305054)
			(stroke
				(width 0.1)
				(type default)
			)
			(layer "F.Fab")
		)
		(pad "1" smd circle
			(at -0.40005 0 90)
			(size 0 0)
			(layers "F.Cu" "F.Mask" "F.Paste")
			(net "BOARD_ID0")
		)
		(pad "2" smd circle
			(at 0.40005 0 90)
			(size 0 0)
			(layers "F.Cu" "F.Mask" "F.Paste")
			(net "P3V3_AUX")
		)
	)
	(footprint ""
		(layer "F.Cu")
		(at 358.013 -212.344 180)
		(property "Reference" "R4095"
			(at 0 0 180)
			(layer "F.SilkS")
			(hide yes)
			(effects
				(font
					(size 1.27 1.27)
				)
			)
		)
		(property "Value" ""
			(at 0 0 180)
			(layer "F.Fab")
			(effects
				(font
					(size 1.27 1.27)
				)
			)
		)
		(duplicate_pad_numbers_are_jumpers no)
		(fp_line
			(start 0.7874 0.4064)
			(end -0.7874 0.4064)
			(stroke
				(width 0.1524)
				(type default)
			)
			(layer "F.SilkS")
		)
		(fp_line
			(start 0.7874 -0.4064)
			(end 0.7874 0.4064)
			(stroke
				(width 0.1524)
				(type default)
			)
			(layer "F.SilkS")
		)
		(fp_line
			(start -0.7874 0.4064)
			(end -0.7874 -0.4064)
			(stroke
				(width 0.1524)
				(type default)
			)
			(layer "F.SilkS")
		)
		(fp_line
			(start -0.7874 -0.4064)
			(end 0.7874 -0.4064)
			(stroke
				(width 0.1524)
				(type default)
			)
			(layer "F.SilkS")
		)
		(fp_line
			(start 0.67945 0.3048)
			(end 0.120396 0.3048)
			(stroke
				(width 0.1)
				(type default)
			)
			(layer "F.Fab")
		)
		(fp_line
			(start 0.67945 -0.3048)
			(end 0.67945 0.3048)
			(stroke
				(width 0.1)
				(type default)
			)
			(layer "F.Fab")
		)
		(fp_line
			(start 0.12065 -0.2794)
			(end 0.12065 -0.3048)
			(stroke
				(width 0.1)
				(type default)
			)
			(layer "F.Fab")
		)
		(fp_line
			(start 0.12065 -0.3048)
			(end 0.67945 -0.3048)
			(stroke
				(width 0.1)
				(type default)
			)
			(layer "F.Fab")
		)
		(fp_line
			(start 0.120396 0.3048)
			(end 0.120396 0.2794)
			(stroke
				(width 0.1)
				(type default)
			)
			(layer "F.Fab")
		)
		(fp_line
			(start 0.120396 0.2794)
			(end -0.12065 0.2794)
			(stroke
				(width 0.1)
				(type default)
			)
			(layer "F.Fab")
		)
		(fp_line
			(start -0.12065 0.3048)
			(end -0.67945 0.3048)
			(stroke
				(width 0.1)
				(type default)
			)
			(layer "F.Fab")
		)
		(fp_line
			(start -0.12065 0.2794)
			(end -0.12065 0.3048)
			(stroke
				(width 0.1)
				(type default)
			)
			(layer "F.Fab")
		)
		(fp_line
			(start -0.12065 -0.2794)
			(end 0.12065 -0.2794)
			(stroke
				(width 0.1)
				(type default)
			)
			(layer "F.Fab")
		)
		(fp_line
			(start -0.12065 -0.305054)
			(end -0.12065 -0.2794)
			(stroke
				(width 0.1)
				(type default)
			)
			(layer "F.Fab")
		)
		(fp_line
			(start -0.67945 0.3048)
			(end -0.67945 -0.305054)
			(stroke
				(width 0.1)
				(type default)
			)
			(layer "F.Fab")
		)
		(fp_line
			(start -0.67945 -0.305054)
			(end -0.12065 -0.305054)
			(stroke
				(width 0.1)
				(type default)
			)
			(layer "F.Fab")
		)
		(pad "1" smd circle
			(at -0.40005 0 180)
			(size 0 0)
			(layers "F.Cu" "F.Mask" "F.Paste")
			(net "PRSNT_NIC3_FPGA_R_N")
		)
		(pad "2" smd circle
			(at 0.40005 0 180)
			(size 0 0)
			(layers "F.Cu" "F.Mask" "F.Paste")
			(net "PRSNT_NIC3_FPGA_N")
		)
	)
	(footprint ""
		(layer "F.Cu")
		(at 251.7267 -55.418228 90)
		(property "Reference" "PC404"
			(at 0 0 90)
			(layer "F.SilkS")
			(hide yes)
			(effects
				(font
					(size 1.27 1.27)
				)
			)
		)
		(property "Value" ""
			(at 0 0 90)
			(layer "F.Fab")
			(effects
				(font
					(size 1.27 1.27)
				)
			)
		)
		(duplicate_pad_numbers_are_jumpers no)
		(fp_line
			(start 0.7874 -0.4064)
			(end 0.7874 0.4064)
			(stroke
				(width 0.1524)
				(type default)
			)
			(layer "F.SilkS")
		)
		(fp_line
			(start -0.7874 -0.4064)
			(end 0.7874 -0.4064)
			(stroke
				(width 0.1524)
				(type default)
			)
			(layer "F.SilkS")
		)
		(fp_line
			(start 0.7874 0.4064)
			(end -0.7874 0.4064)
			(stroke
				(width 0.1524)
				(type default)
			)
			(layer "F.SilkS")
		)
		(fp_line
			(start -0.7874 0.4064)
			(end -0.7874 -0.4064)
			(stroke
				(width 0.1524)
				(type default)
			)
			(layer "F.SilkS")
		)
		(fp_line
			(start -0.12065 -0.305054)
			(end -0.12065 -0.2794)
			(stroke
				(width 0.1)
				(type default)
			)
			(layer "F.Fab")
		)
		(fp_line
			(start -0.67945 -0.305054)
			(end -0.12065 -0.305054)
			(stroke
				(width 0.1)
				(type default)
			)
			(layer "F.Fab")
		)
		(fp_line
			(start 0.67945 -0.3048)
			(end 0.67945 0.3048)
			(stroke
				(width 0.1)
				(type default)
			)
			(layer "F.Fab")
		)
		(fp_line
			(start 0.12065 -0.3048)
			(end 0.67945 -0.3048)
			(stroke
				(width 0.1)
				(type default)
			)
			(layer "F.Fab")
		)
		(fp_line
			(start 0.12065 -0.2794)
			(end 0.12065 -0.3048)
			(stroke
				(width 0.1)
				(type default)
			)
			(layer "F.Fab")
		)
		(fp_line
			(start -0.12065 -0.2794)
			(end 0.12065 -0.2794)
			(stroke
				(width 0.1)
				(type default)
			)
			(layer "F.Fab")
		)
		(fp_line
			(start 0.120396 0.2794)
			(end -0.12065 0.2794)
			(stroke
				(width 0.1)
				(type default)
			)
			(layer "F.Fab")
		)
		(fp_line
			(start -0.12065 0.2794)
			(end -0.12065 0.3048)
			(stroke
				(width 0.1)
				(type default)
			)
			(layer "F.Fab")
		)
		(fp_line
			(start 0.67945 0.3048)
			(end 0.120396 0.3048)
			(stroke
				(width 0.1)
				(type default)
			)
			(layer "F.Fab")
		)
		(fp_line
			(start 0.120396 0.3048)
			(end 0.120396 0.2794)
			(stroke
				(width 0.1)
				(type default)
			)
			(layer "F.Fab")
		)
		(fp_line
			(start -0.12065 0.3048)
			(end -0.67945 0.3048)
			(stroke
				(width 0.1)
				(type default)
			)
			(layer "F.Fab")
		)
		(fp_line
			(start -0.67945 0.3048)
			(end -0.67945 -0.305054)
			(stroke
				(width 0.1)
				(type default)
			)
			(layer "F.Fab")
		)
		(pad "1" smd circle
			(at -0.40005 0 90)
			(size 0 0)
			(layers "F.Cu" "F.Mask" "F.Paste")
			(net "P12V_SSD8_R")
		)
		(pad "2" smd circle
			(at 0.40005 0 90)
			(size 0 0)
			(layers "F.Cu" "F.Mask" "F.Paste")
			(net "GND")
		)
	)
)
